# T6G (Grand Teton) — schematic parts with pin connectivity, parts 8081–8081 of 8303; source: Cadence DE-HDL packaged netlist (pstxprt.dat, pstxnet.dat, pstchip.dat)

U25  GENOA_SP5  SOCKET6096_13568-001 IO  pkg SOCKET6096_93-4X120-45XA  page 10  (pins 2353-2688 of 6096)
  BR58  VDDIO_BR58  POWER  = PVDDIO_P0
  BR59  VSS_BR59  POWER  = GND
  BR60  MDB1_RSP_L  IN  = NC
  BR61  VSS_BR61  POWER  = GND
  BR62  VSS_BR62  POWER  = GND
  BR63  VSS_BR63  POWER  = GND
  BR64  MBB1_RSP_L  IN  = NC
  BR65  VDDIO_BR65  POWER  = PVDDIO_P0
  BR66  VSS_BR66  POWER  = GND
  BR67  MFB1_RSP_L  IN  = NC
  BR68  VSS_BR68  POWER  = GND
  BR69  VSS_BR69  POWER  = GND
  BR70  VSS_BR70  POWER  = GND
  BR71  MEB1_RSP_L  IN  = NC
  BR72  VDDIO_BR72  POWER  = PVDDIO_P0
  BR73  VSS_BR73  POWER  = GND
  BR74  MAB1_RSP_L  IN  = NC
  BR75  VSS_BR75  POWER  = GND
  BT2  MGB_CHECK4  BI  = M_G_CPU0_SB_CB<4>
  BT3  VSS_BT3  POWER  = GND
  BT4  VSS_BT4  POWER  = GND
  BT5  VSS_BT5  POWER  = GND
  BT6  MKB_CHECK4  BI  = M_K_CPU0_SB_CB<4>
  BT7  VSS_BT7  POWER  = GND
  BT8  VSS_BT8  POWER  = GND
  BT9  MLB_CHECK4  BI  = M_L_CPU0_SB_CB<4>
  BT10  VSS_BT10  POWER  = GND
  BT11  VSS_BT11  POWER  = GND
  BT12  VSS_BT12  POWER  = GND
  BT13  MHB_CHECK4  BI  = M_H_CPU0_SB_CB<4>
  BT14  VSS_BT14  POWER  = GND
  BT15  VSS_BT15  POWER  = GND
  BT16  MJB_CHECK4  BI  = M_J_CPU0_SB_CB<4>
  BT17  VSS_BT17  POWER  = GND
  BT18  VSS_BT18  POWER  = GND
  BT19  VSS_BT19  POWER  = GND
  BT20  MIB_CHECK4  BI  = M_I_CPU0_SB_CB<4>
  BT21  VSS_BT21  POWER  = GND
  BT22  VSS_BT22  POWER  = GND
  BT23  VDDCR_CPU1_BT23  POWER  = PVDDCR_CPU1_P0
  BT24  VDDCR_CPU1_BT24  POWER  = PVDDCR_CPU1_P0
  BT25  VSS_BT25  POWER  = GND
  BT26  VDDCR_CPU1_BT26  POWER  = PVDDCR_CPU1_P0
  BT27  VDDCR_CPU1_BT27  POWER  = PVDDCR_CPU1_P0
  BT28  VSS_BT28  POWER  = GND
  BT29  VDDCR_CPU1_BT29  POWER  = PVDDCR_CPU1_P0
  BT30  VDDCR_CPU1_BT30  POWER  = PVDDCR_CPU1_P0
  BT31  VSS_BT31  POWER  = GND
  BT32  VDDCR_CPU1_BT32  POWER  = PVDDCR_CPU1_P0
  BT33  VDDCR_CPU1_BT33  POWER  = PVDDCR_CPU1_P0
  BT34  VSS_BT34  POWER  = GND
  BT35  P2_TXN0  OUT  = P5E_CPU0_P2_TX_DN<0>
  BT36  P2_TXP0  OUT  = P5E_CPU0_P2_TX_DP<0>
  BT37  VSS_BT37  POWER  = GND
  BT39  VSS_BT39  POWER  = GND
  BT40  \p0_rxp15||sata17_rxp\  IN  = P5E_CPU0_P0_RX_DP<15>
  BT41  \p0_rxn15||sata17_rxn\  IN  = P5E_CPU0_P0_RX_DN<15>
  BT42  VSS_BT42  POWER  = GND
  BT43  VDDCR_CPU1_BT43  POWER  = PVDDCR_CPU1_P0
  BT44  VDDCR_CPU1_BT44  POWER  = PVDDCR_CPU1_P0
  BT45  VSS_BT45  POWER  = GND
  BT46  VDDCR_CPU1_BT46  POWER  = PVDDCR_CPU1_P0
  BT47  VDDCR_CPU1_BT47  POWER  = PVDDCR_CPU1_P0
  BT48  VSS_BT48  POWER  = GND
  BT49  VDDCR_CPU1_BT49  POWER  = PVDDCR_CPU1_P0
  BT50  VDDCR_CPU1_BT50  POWER  = PVDDCR_CPU1_P0
  BT51  VSS_BT51  POWER  = GND
  BT52  VDDCR_CPU1_BT52  POWER  = PVDDCR_CPU1_P0
  BT53  VDDCR_CPU1_BT53  POWER  = PVDDCR_CPU1_P0
  BT54  VSS_BT54  POWER  = GND
  BT55  VSS_BT55  POWER  = GND
  BT56  MCB_CHECK4  BI  = M_C_CPU0_SB_CB<4>
  BT57  VSS_BT57  POWER  = GND
  BT58  VSS_BT58  POWER  = GND
  BT59  VSS_BT59  POWER  = GND
  BT60  MDB_CHECK4  BI  = M_D_CPU0_SB_CB<4>
  BT61  VSS_BT61  POWER  = GND
  BT62  VSS_BT62  POWER  = GND
  BT63  MBB_CHECK4  BI  = M_B_CPU0_SB_CB<4>
  BT64  VSS_BT64  POWER  = GND
  BT65  VSS_BT65  POWER  = GND
  BT66  VSS_BT66  POWER  = GND
  BT67  MFB_CHECK4  BI  = M_F_CPU0_SB_CB<4>
  BT68  VSS_BT68  POWER  = GND
  BT69  VSS_BT69  POWER  = GND
  BT70  MEB_CHECK4  BI  = M_E_CPU0_SB_CB<4>
  BT71  VSS_BT71  POWER  = GND
  BT72  VSS_BT72  POWER  = GND
  BT73  VSS_BT73  POWER  = GND
  BT74  MAB_CHECK4  BI  = M_A_CPU0_SB_CB<4>
  BU1  VSS_BU1  POWER  = GND
  BU2  MGB_CHECK6  BI  = M_G_CPU0_SB_CB<6>
  BU3  MGB_CHECK5  BI  = M_G_CPU0_SB_CB<5>
  BU4  VSS_BU4  POWER  = GND
  BU5  MKB_CHECK6  BI  = M_K_CPU0_SB_CB<6>
  BU6  VSS_BU6  POWER  = GND
  BU7  MKB_CHECK5  BI  = M_K_CPU0_SB_CB<5>
  BU8  VSS_BU8  POWER  = GND
  BU9  MLB_CHECK6  BI  = M_L_CPU0_SB_CB<6>
  BU10  MLB_CHECK5  BI  = M_L_CPU0_SB_CB<5>
  BU11  VSS_BU11  POWER  = GND
  BU12  MHB_CHECK6  BI  = M_H_CPU0_SB_CB<6>
  BU13  VSS_BU13  POWER  = GND
  BU14  MHB_CHECK5  BI  = M_H_CPU0_SB_CB<5>
  BU15  VSS_BU15  POWER  = GND
  BU16  MJB_CHECK6  BI  = M_J_CPU0_SB_CB<6>
  BU17  MJB_CHECK5  BI  = M_J_CPU0_SB_CB<5>
  BU18  VSS_BU18  POWER  = GND
  BU19  MIB_CHECK6  BI  = M_I_CPU0_SB_CB<6>
  BU20  VSS_BU20  POWER  = GND
  BU21  MIB_CHECK5  BI  = M_I_CPU0_SB_CB<5>
  BU22  VSS_BU22  POWER  = GND
  BU23  P2_TXN13  OUT  = P5E_CPU0_P2_TX_DN<13>
  BU24  P2_TXP13  OUT  = P5E_CPU0_P2_TX_DP<13>
  BU25  VSS_BU25  POWER  = GND
  BU26  P2_TXN10  OUT  = P5E_CPU0_P2_TX_DN<10>
  BU27  P2_TXP10  OUT  = P5E_CPU0_P2_TX_DP<10>
  BU28  VSS_BU28  POWER  = GND
  BU29  P2_TXN7  OUT  = P5E_CPU0_P2_TX_DN<7>
  BU30  P2_TXP7  OUT  = P5E_CPU0_P2_TX_DP<7>
  BU31  VSS_BU31  POWER  = GND
  BU32  P2_TXN4  OUT  = P5E_CPU0_P2_TX_DN<4>
  BU33  P2_TXP4  OUT  = P5E_CPU0_P2_TX_DP<4>
  BU34  VSS_BU34  POWER  = GND
  BU35  VSS_BU35  POWER  = GND
  BU36  VSS_BU36  POWER  = GND
  BU40  VSS_BU40  POWER  = GND
  BU41  VSS_BU41  POWER  = GND
  BU42  VSS_BU42  POWER  = GND
  BU43  \p0_rxp11||sata13_rxp\  IN  = P5E_CPU0_P0_RX_DP<11>
  BU44  \p0_rxn11||sata13_rxn\  IN  = P5E_CPU0_P0_RX_DN<11>
  BU45  VSS_BU45  POWER  = GND
  BU46  \p0_rxp8||sata10_rxp\  IN  = P5E_CPU0_P0_RX_DP<8>
  BU47  \p0_rxn8||sata10_rxn\  IN  = P5E_CPU0_P0_RX_DN<8>
  BU48  VSS_BU48  POWER  = GND
  BU49  \p0_rxp5||sata05_rxp\  IN  = P5E_CPU0_P0_RX_DP<5>
  BU50  \p0_rxn5||sata05_rxn\  IN  = P5E_CPU0_P0_RX_DN<5>
  BU51  VSS_BU51  POWER  = GND
  BU52  \p0_rxp2||sata02_rxp\  IN  = P5E_CPU0_P0_RX_DP<2>
  BU53  \p0_rxn2||sata02_rxn\  IN  = P5E_CPU0_P0_RX_DN<2>
  BU54  VSS_BU54  POWER  = GND
  BU55  MCB_CHECK5  BI  = M_C_CPU0_SB_CB<5>
  BU56  VSS_BU56  POWER  = GND
  BU57  MCB_CHECK6  BI  = M_C_CPU0_SB_CB<6>
  BU58  VSS_BU58  POWER  = GND
  BU59  MDB_CHECK5  BI  = M_D_CPU0_SB_CB<5>
  BU60  MDB_CHECK6  BI  = M_D_CPU0_SB_CB<6>
  BU61  VSS_BU61  POWER  = GND
  BU62  MBB_CHECK5  BI  = M_B_CPU0_SB_CB<5>
  BU63  VSS_BU63  POWER  = GND
  BU64  MBB_CHECK6  BI  = M_B_CPU0_SB_CB<6>
  BU65  VSS_BU65  POWER  = GND
  BU66  MFB_CHECK5  BI  = M_F_CPU0_SB_CB<5>
  BU67  MFB_CHECK6  BI  = M_F_CPU0_SB_CB<6>
  BU68  VSS_BU68  POWER  = GND
  BU69  MEB_CHECK5  BI  = M_E_CPU0_SB_CB<5>
  BU70  VSS_BU70  POWER  = GND
  BU71  MEB_CHECK6  BI  = M_E_CPU0_SB_CB<6>
  BU72  VSS_BU72  POWER  = GND
  BU73  MAB_CHECK5  BI  = M_A_CPU0_SB_CB<5>
  BU74  MAB_CHECK6  BI  = M_A_CPU0_SB_CB<6>
  BU75  VSS_BU75  POWER  = GND
  BV2  MGB_DQS_H9  BI  = M_G_CPU0_SB_DQS_DP<9>
  BV3  VSS_BV3  POWER  = GND
  BV4  MGB_CHECK7  BI  = M_G_CPU0_SB_CB<7>
  BV5  VDD_11_S3_BV5  POWER  = PVDD11_S3_P0
  BV6  MKB_DQS_H9  BI  = M_K_CPU0_SB_DQS_DP<9>
  BV7  MKB_CHECK7  BI  = M_K_CPU0_SB_CB<7>
  BV8  VSS_BV8  POWER  = GND
  BV9  MLB_DQS_H9  BI  = M_L_CPU0_SB_DQS_DP<9>
  BV10  VSS_BV10  POWER  = GND
  BV11  MLB_CHECK7  BI  = M_L_CPU0_SB_CB<7>
  BV12  VDD_11_S3_BV12  POWER  = PVDD11_S3_P0
  BV13  MHB_DQS_H9  BI  = M_H_CPU0_SB_DQS_DP<9>
  BV14  MHB_CHECK7  BI  = M_H_CPU0_SB_CB<7>
  BV15  VSS_BV15  POWER  = GND
  BV16  MJB_DQS_H9  BI  = M_J_CPU0_SB_DQS_DP<9>
  BV17  VSS_BV17  POWER  = GND
  BV18  MJB_CHECK7  BI  = M_J_CPU0_SB_CB<7>
  BV19  VDD_11_S3_BV19  POWER  = PVDD11_S3_P0
  BV20  MIB_DQS_H9  BI  = M_I_CPU0_SB_DQS_DP<9>
  BV21  MIB_CHECK7  BI  = M_I_CPU0_SB_CB<7>
  BV22  VDD_11_S3_BV22  POWER  = PVDD11_S3_P0
  BV23  VSS_BV23  POWER  = GND
  BV24  VSS_BV24  POWER  = GND
  BV25  VSS_BV25  POWER  = GND
  BV26  VSS_BV26  POWER  = GND
  BV27  VSS_BV27  POWER  = GND
  BV28  VSS_BV28  POWER  = GND
  BV29  VSS_BV29  POWER  = GND
  BV30  VSS_BV30  POWER  = GND
  BV31  VSS_BV31  POWER  = GND
  BV32  VSS_BV32  POWER  = GND
  BV33  VSS_BV33  POWER  = GND
  BV34  VSS_BV34  POWER  = GND
  BV35  P2_TXN1  OUT  = P5E_CPU0_P2_TX_DN<1>
  BV36  P2_TXP1  OUT  = P5E_CPU0_P2_TX_DP<1>
  BV37  VSS_BV37  POWER  = GND
  BV39  VSS_BV39  POWER  = GND
  BV40  \p0_rxp14||sata16_rxp\  IN  = P5E_CPU0_P0_RX_DP<14>
  BV41  \p0_rxn14||sata16_rxn\  IN  = P5E_CPU0_P0_RX_DN<14>
  BV42  VSS_BV42  POWER  = GND
  BV43  VSS_BV43  POWER  = GND
  BV44  VSS_BV44  POWER  = GND
  BV45  VSS_BV45  POWER  = GND
  BV46  VSS_BV46  POWER  = GND
  BV47  VSS_BV47  POWER  = GND
  BV48  VSS_BV48  POWER  = GND
  BV49  VSS_BV49  POWER  = GND
  BV50  VSS_BV50  POWER  = GND
  BV51  VSS_BV51  POWER  = GND
  BV52  VSS_BV52  POWER  = GND
  BV53  VSS_BV53  POWER  = GND
  BV54  VDDIO_BV54  POWER  = PVDDIO_P0
  BV55  MCB_CHECK7  BI  = M_C_CPU0_SB_CB<7>
  BV56  MCB_DQS_H9  BI  = M_C_CPU0_SB_DQS_DP<9>
  BV57  VDDIO_BV57  POWER  = PVDDIO_P0
  BV58  MDB_CHECK7  BI  = M_D_CPU0_SB_CB<7>
  BV59  VSS_BV59  POWER  = GND
  BV60  MDB_DQS_H9  BI  = M_D_CPU0_SB_DQS_DP<9>
  BV61  VSS_BV61  POWER  = GND
  BV62  MBB_CHECK7  BI  = M_B_CPU0_SB_CB<7>
  BV63  MBB_DQS_H9  BI  = M_B_CPU0_SB_DQS_DP<9>
  BV64  VDDIO_BV64  POWER  = PVDDIO_P0
  BV65  MFB_CHECK7  BI  = M_F_CPU0_SB_CB<7>
  BV66  VSS_BV66  POWER  = GND
  BV67  MFB_DQS_H9  BI  = M_F_CPU0_SB_DQS_DP<9>
  BV68  VSS_BV68  POWER  = GND
  BV69  MEB_CHECK7  BI  = M_E_CPU0_SB_CB<7>
  BV70  MEB_DQS_H9  BI  = M_E_CPU0_SB_DQS_DP<9>
  BV71  VDDIO_BV71  POWER  = PVDDIO_P0
  BV72  MAB_CHECK7  BI  = M_A_CPU0_SB_CB<7>
  BV73  VSS_BV73  POWER  = GND
  BV74  MAB_DQS_H9  BI  = M_A_CPU0_SB_DQS_DP<9>
  BW1  VSS_BW1  POWER  = GND
  BW2  MGB_DQS_L9  BI  = M_G_CPU0_SB_DQS_DN<9>
  BW3  MGB_DQS_L4  BI  = M_G_CPU0_SB_DQS_DN<4>
  BW4  VSS_BW4  POWER  = GND
  BW5  MKB_DQS_L9  BI  = M_K_CPU0_SB_DQS_DN<9>
  BW6  VSS_BW6  POWER  = GND
  BW7  MKB_DQS_L4  BI  = M_K_CPU0_SB_DQS_DN<4>
  BW8  VSS_BW8  POWER  = GND
  BW9  MLB_DQS_L9  BI  = M_L_CPU0_SB_DQS_DN<9>
  BW10  MLB_DQS_L4  BI  = M_L_CPU0_SB_DQS_DN<4>
  BW11  VSS_BW11  POWER  = GND
  BW12  MHB_DQS_L9  BI  = M_H_CPU0_SB_DQS_DN<9>
  BW13  VSS_BW13  POWER  = GND
  BW14  MHB_DQS_L4  BI  = M_H_CPU0_SB_DQS_DN<4>
  BW15  VSS_BW15  POWER  = GND
  BW16  MJB_DQS_L9  BI  = M_J_CPU0_SB_DQS_DN<9>
  BW17  MJB_DQS_L4  BI  = M_J_CPU0_SB_DQS_DN<4>
  BW18  VSS_BW18  POWER  = GND
  BW19  MIB_DQS_L9  BI  = M_I_CPU0_SB_DQS_DN<9>
  BW20  VSS_BW20  POWER  = GND
  BW21  MIB_DQS_L4  BI  = M_I_CPU0_SB_DQS_DN<4>
  BW22  VSS_BW22  POWER  = GND
  BW23  P2_TXN15  OUT  = P5E_CPU0_P2_TX_DN<15>
  BW24  P2_TXP15  OUT  = P5E_CPU0_P2_TX_DP<15>
  BW25  VSS_BW25  POWER  = GND
  BW26  P2_TXN12  OUT  = P5E_CPU0_P2_TX_DN<12>
  BW27  P2_TXP12  OUT  = P5E_CPU0_P2_TX_DP<12>
  BW28  VSS_BW28  POWER  = GND
  BW29  P2_TXN9  OUT  = P5E_CPU0_P2_TX_DN<9>
  BW30  P2_TXP9  OUT  = P5E_CPU0_P2_TX_DP<9>
  BW31  VSS_BW31  POWER  = GND
  BW32  P2_TXN6  OUT  = P5E_CPU0_P2_TX_DN<6>
  BW33  P2_TXP6  OUT  = P5E_CPU0_P2_TX_DP<6>
  BW34  VSS_BW34  POWER  = GND
  BW35  VDDCR_CPU1_BW35  POWER  = PVDDCR_CPU1_P0
  BW36  VDDCR_CPU1_BW36  POWER  = PVDDCR_CPU1_P0
  BW40  VDDCR_CPU1_BW40  POWER  = PVDDCR_CPU1_P0
  BW41  VDDCR_CPU1_BW41  POWER  = PVDDCR_CPU1_P0
  BW42  VSS_BW42  POWER  = GND
  BW43  \p0_rxp9||sata11_rxp\  IN  = P5E_CPU0_P0_RX_DP<9>
  BW44  \p0_rxn9||sata11_rxn\  IN  = P5E_CPU0_P0_RX_DN<9>
  BW45  VSS_BW45  POWER  = GND
  BW46  \p0_rxp6||sata06_rxp\  IN  = P5E_CPU0_P0_RX_DP<6>
  BW47  \p0_rxn6||sata06_rxn\  IN  = P5E_CPU0_P0_RX_DN<6>
  BW48  VSS_BW48  POWER  = GND
  BW49  \p0_rxp3||sata03_rxp\  IN  = P5E_CPU0_P0_RX_DP<3>
  BW50  \p0_rxn3||sata03_rxn\  IN  = P5E_CPU0_P0_RX_DN<3>
  BW51  VSS_BW51  POWER  = GND
  BW52  \p0_rxp0||sata00_rxp\  IN  = P5E_CPU0_P0_RX_DP<0>
  BW53  \p0_rxn0||sata00_rxn\  IN  = P5E_CPU0_P0_RX_DN<0>
  BW54  VSS_BW54  POWER  = GND
  BW55  MCB_DQS_L4  BI  = M_C_CPU0_SB_DQS_DN<4>
  BW56  VSS_BW56  POWER  = GND
  BW57  MCB_DQS_L9  BI  = M_C_CPU0_SB_DQS_DN<9>
  BW58  VSS_BW58  POWER  = GND
  BW59  MDB_DQS_L4  BI  = M_D_CPU0_SB_DQS_DN<4>
  BW60  MDB_DQS_L9  BI  = M_D_CPU0_SB_DQS_DN<9>
  BW61  VSS_BW61  POWER  = GND
  BW62  MBB_DQS_L4  BI  = M_B_CPU0_SB_DQS_DN<4>
  BW63  VSS_BW63  POWER  = GND
  BW64  MBB_DQS_L9  BI  = M_B_CPU0_SB_DQS_DN<9>
  BW65  VSS_BW65  POWER  = GND
  BW66  MFB_DQS_L4  BI  = M_F_CPU0_SB_DQS_DN<4>
  BW67  MFB_DQS_L9  BI  = M_F_CPU0_SB_DQS_DN<9>
  BW68  VSS_BW68  POWER  = GND
  BW69  MEB_DQS_L4  BI  = M_E_CPU0_SB_DQS_DN<4>
  BW70  VSS_BW70  POWER  = GND
  BW71  MEB_DQS_L9  BI  = M_E_CPU0_SB_DQS_DN<9>
  BW72  VSS_BW72  POWER  = GND
  BW73  MAB_DQS_L4  BI  = M_A_CPU0_SB_DQS_DN<4>
  BW74  MAB_DQS_L9  BI  = M_A_CPU0_SB_DQS_DN<9>
  BW75  VSS_BW75  POWER  = GND
  BY2  MGB_CHECK0  BI  = M_G_CPU0_SB_CB<0>
  BY3  VSS_BY3  POWER  = GND
  BY4  MGB_DQS_H4  BI  = M_G_CPU0_SB_DQS_DP<4>
  BY5  VSS_BY5  POWER  = GND
  BY6  MKB_CHECK0  BI  = M_K_CPU0_SB_CB<0>
  BY7  MKB_DQS_H4  BI  = M_K_CPU0_SB_DQS_DP<4>
  BY8  VSS_BY8  POWER  = GND
  BY9  MLB_CHECK0  BI  = M_L_CPU0_SB_CB<0>
  BY10  VSS_BY10  POWER  = GND
  BY11  MLB_DQS_H4  BI  = M_L_CPU0_SB_DQS_DP<4>
  BY12  VSS_BY12  POWER  = GND
  BY13  MHB_CHECK0  BI  = M_H_CPU0_SB_CB<0>
  BY14  MHB_DQS_H4  BI  = M_H_CPU0_SB_DQS_DP<4>
  BY15  VSS_BY15  POWER  = GND
  BY16  MJB_CHECK0  BI  = M_J_CPU0_SB_CB<0>
  BY17  VSS_BY17  POWER  = GND
  BY18  MJB_DQS_H4  BI  = M_J_CPU0_SB_DQS_DP<4>
  BY19  VSS_BY19  POWER  = GND
  BY20  MIB_CHECK0  BI  = M_I_CPU0_SB_CB<0>
  BY21  MIB_DQS_H4  BI  = M_I_CPU0_SB_DQS_DP<4>
  BY22  VSS_BY22  POWER  = GND
  BY23  VDDCR_CPU1_BY23  POWER  = PVDDCR_CPU1_P0
  BY24  VDDCR_CPU1_BY24  POWER  = PVDDCR_CPU1_P0
  BY25  VSS_BY25  POWER  = GND
  BY26  VDDCR_CPU1_BY26  POWER  = PVDDCR_CPU1_P0
  BY27  VDDCR_CPU1_BY27  POWER  = PVDDCR_CPU1_P0
  BY28  VSS_BY28  POWER  = GND
  BY29  VDDCR_CPU1_BY29  POWER  = PVDDCR_CPU1_P0
  BY30  VDDCR_CPU1_BY30  POWER  = PVDDCR_CPU1_P0
  BY31  VSS_BY31  POWER  = GND
